(kicad_pcb
	(version 20260206)
	(generator "pcbnew")
	(generator_version "10.0")
	(general
		(thickness 1.6)
		(legacy_teardrops no)
	)
	(paper "A4")
	(title_block
		(title "peb — Lightning_PEB_BRD.brd")
		(comment 1 "Lightning (Wiwynn / Facebook NVMe JBOF) / footprints 1452-1459 of 2563")
	)
	(layers
		(0 "F.Cu" signal "TOP")
		(4 "In1.Cu" signal "L2GND")
		(6 "In2.Cu" signal "L3")
		(8 "In3.Cu" signal "L4VCC")
		(10 "In4.Cu" signal "L5VCC")
		(12 "In5.Cu" signal "L6")
		(14 "In6.Cu" signal "L7GND")
		(2 "B.Cu" signal "BOTTOM")
		(9 "F.Adhes" user "F.Adhesive")
		(11 "B.Adhes" user "B.Adhesive")
		(13 "F.Paste" user "Package Geometry/Pastemask Top")
		(15 "B.Paste" user "Package Geometry/Pastemask Bottom")
		(5 "F.SilkS" user "Ref Des/Silkscreen Top")
		(7 "B.SilkS" user "Ref Des/Silkscreen Bottom")
		(1 "F.Mask" user "Board Geometry/Soldermask Top")
		(3 "B.Mask" user "Board Geometry/Soldermask Bottom")
		(17 "Dwgs.User" user "User.Drawings")
		(19 "Cmts.User" user "User.Comments")
		(21 "Eco1.User" user "User.Eco1")
		(23 "Eco2.User" user "User.Eco2")
		(25 "Edge.Cuts" user "Board Geometry/Outline")
		(27 "Margin" user)
		(31 "F.CrtYd" user "Package Geometry/Place Bound Top")
		(29 "B.CrtYd" user "Package Geometry/Place Bound Bottom")
		(35 "F.Fab" user "Ref Des/Assembly Top")
		(33 "B.Fab" user "Ref Des/Assembly Bottom")
	)
	(footprint ""
		(layer "F.Cu")
		(at 219.413582 -11.184636 90)
		(property "Reference" "R661"
			(at 0 0 90)
			(layer "F.SilkS")
			(hide yes)
			(effects
				(font
					(size 1.27 1.27)
				)
			)
		)
		(property "Value" "100KR2F-L1-GP"
			(at 0.064008 -3.993896 90)
			(unlocked yes)
			(layer "F.Fab")
			(hide yes)
			(effects
				(font
					(size 1.016 1.016)
					(thickness 0.1524)
				)
			)
		)
		(property "Device Type" "R402H16"
			(at 0.064008 -5.517896 90)
			(unlocked yes)
			(layer "F.Fab")
			(hide yes)
			(effects
				(font
					(size 1.016 1.016)
					(thickness 0.1524)
				)
			)
		)
		(duplicate_pad_numbers_are_jumpers no)
		(fp_line
			(start 0.508 -0.9398)
			(end -0.508 -0.9398)
			(stroke
				(width 0.1524)
				(type default)
			)
			(layer "F.SilkS")
		)
		(fp_line
			(start -0.508 -0.9398)
			(end -0.508 0.9398)
			(stroke
				(width 0.1524)
				(type default)
			)
			(layer "F.SilkS")
		)
		(fp_rect
			(start -0.508 0.9398)
			(end 0.508 -0.9398)
			(stroke
				(width 0)
				(type default)
			)
			(fill no)
			(layer "F.CrtYd")
		)
		(fp_rect
			(start -0.508 0.9398)
			(end 0.508 -0.9398)
			(stroke
				(width 0)
				(type default)
			)
			(fill no)
			(layer "F.Fab")
		)
		(pad "1" smd custom
			(at 0 -0.4445 90)
			(size 0.1397 0.1397)
			(layers "F.Cu" "F.Mask" "F.Paste")
			(net "P3V3_STBY")
			(options
				(clearance outline)
				(anchor circle)
			)
			(primitives
				(gr_poly
					(pts
						(arc
							(start -0.1778 -0.2794)
							(mid -0.249642 -0.249642)
							(end -0.2794 -0.1778)
						)
						(arc
							(start -0.2794 0.1778)
							(mid -0.249642 0.249642)
							(end -0.1778 0.2794)
						)
						(arc
							(start 0.1778 0.2794)
							(mid 0.249642 0.249642)
							(end 0.2794 0.1778)
						)
						(arc
							(start 0.2794 -0.1778)
							(mid 0.249642 -0.249642)
							(end 0.1778 -0.2794)
						)
					)
					(width 0)
					(fill yes)
				)
			)
		)
		(pad "2" smd custom
			(at 0 0.4445 90)
			(size 0.1397 0.1397)
			(layers "F.Cu" "F.Mask" "F.Paste")
			(net "EEPROM_A0")
			(options
				(clearance outline)
				(anchor circle)
			)
			(primitives
				(gr_poly
					(pts
						(arc
							(start -0.1778 -0.2794)
							(mid -0.249642 -0.249642)
							(end -0.2794 -0.1778)
						)
						(arc
							(start -0.2794 0.1778)
							(mid -0.249642 0.249642)
							(end -0.1778 0.2794)
						)
						(arc
							(start 0.1778 0.2794)
							(mid 0.249642 0.249642)
							(end 0.2794 0.1778)
						)
						(arc
							(start 0.2794 -0.1778)
							(mid 0.249642 -0.249642)
							(end 0.1778 -0.2794)
						)
					)
					(width 0)
					(fill yes)
				)
			)
		)
	)
	(footprint ""
		(layer "F.Cu")
		(at 128.7272 -47.371 90)
		(property "Reference" "R773"
			(at 0 0 90)
			(layer "F.SilkS")
			(hide yes)
			(effects
				(font
					(size 1.27 1.27)
				)
			)
		)
		(property "Value" "1KR2F-3-GP"
			(at 0.064008 -3.993896 90)
			(unlocked yes)
			(layer "F.Fab")
			(hide yes)
			(effects
				(font
					(size 1.016 1.016)
					(thickness 0.1524)
				)
			)
		)
		(property "Device Type" "R402H16"
			(at 0.064008 -5.517896 90)
			(unlocked yes)
			(layer "F.Fab")
			(hide yes)
			(effects
				(font
					(size 1.016 1.016)
					(thickness 0.1524)
				)
			)
		)
		(duplicate_pad_numbers_are_jumpers no)
		(fp_line
			(start 0.508 -0.9398)
			(end -0.508 -0.9398)
			(stroke
				(width 0.1524)
				(type default)
			)
			(layer "F.SilkS")
		)
		(fp_line
			(start -0.508 -0.9398)
			(end -0.508 0.9398)
			(stroke
				(width 0.1524)
				(type default)
			)
			(layer "F.SilkS")
		)
		(fp_rect
			(start -0.508 0.9398)
			(end 0.508 -0.9398)
			(stroke
				(width 0)
				(type default)
			)
			(fill no)
			(layer "F.CrtYd")
		)
		(fp_rect
			(start -0.508 0.9398)
			(end 0.508 -0.9398)
			(stroke
				(width 0)
				(type default)
			)
			(fill no)
			(layer "F.Fab")
		)
		(pad "1" smd custom
			(at 0 -0.4445 90)
			(size 0.1397 0.1397)
			(layers "F.Cu" "F.Mask" "F.Paste")
			(net "EJTAG_TRSTB")
			(options
				(clearance outline)
				(anchor circle)
			)
			(primitives
				(gr_poly
					(pts
						(arc
							(start -0.1778 -0.2794)
							(mid -0.249642 -0.249642)
							(end -0.2794 -0.1778)
						)
						(arc
							(start -0.2794 0.1778)
							(mid -0.249642 0.249642)
							(end -0.1778 0.2794)
						)
						(arc
							(start 0.1778 0.2794)
							(mid 0.249642 0.249642)
							(end 0.2794 0.1778)
						)
						(arc
							(start 0.2794 -0.1778)
							(mid 0.249642 -0.249642)
							(end 0.1778 -0.2794)
						)
					)
					(width 0)
					(fill yes)
				)
			)
		)
		(pad "2" smd custom
			(at 0 0.4445 90)
			(size 0.1397 0.1397)
			(layers "F.Cu" "F.Mask" "F.Paste")
			(net "GND")
			(options
				(clearance outline)
				(anchor circle)
			)
			(primitives
				(gr_poly
					(pts
						(arc
							(start -0.1778 -0.2794)
							(mid -0.249642 -0.249642)
							(end -0.2794 -0.1778)
						)
						(arc
							(start -0.2794 0.1778)
							(mid -0.249642 0.249642)
							(end -0.1778 0.2794)
						)
						(arc
							(start 0.1778 0.2794)
							(mid 0.249642 0.249642)
							(end 0.2794 0.1778)
						)
						(arc
							(start 0.2794 -0.1778)
							(mid 0.249642 -0.249642)
							(end 0.1778 -0.2794)
						)
					)
					(width 0)
					(fill yes)
				)
			)
		)
	)
	(footprint ""
		(layer "F.Cu")
		(at 76.581 -123.2662 180)
		(property "Reference" "C281"
			(at 0 0 180)
			(layer "F.SilkS")
			(hide yes)
			(effects
				(font
					(size 1.27 1.27)
				)
			)
		)
		(property "Value" "SCD1U16V2KX-3GP"
			(at 1.1811 -2.7051 180)
			(unlocked yes)
			(layer "F.Fab")
			(hide yes)
			(effects
				(font
					(size 1.016 1.016)
					(thickness 0.1524)
				)
			)
		)
		(property "Device Type" "C402H22"
			(at 1.1811 -4.2291 180)
			(unlocked yes)
			(layer "F.Fab")
			(hide yes)
			(effects
				(font
					(size 1.016 1.016)
					(thickness 0.1524)
				)
			)
		)
		(duplicate_pad_numbers_are_jumpers no)
		(fp_rect
			(start -0.4318 0.9525)
			(end 0.4318 -0.9525)
			(stroke
				(width 0)
				(type default)
			)
			(fill no)
			(layer "F.CrtYd")
		)
		(fp_rect
			(start -0.4318 0.9525)
			(end 0.4318 -0.9525)
			(stroke
				(width 0)
				(type default)
			)
			(fill no)
			(layer "F.Fab")
		)
		(pad "1" smd custom
			(at 0 -0.4445 180)
			(size 0.1524 0.1524)
			(layers "F.Cu" "F.Mask" "F.Paste")
			(net "P3V3_STBY")
			(options
				(clearance outline)
				(anchor circle)
			)
			(primitives
				(gr_poly
					(pts
						(arc
							(start 0.3048 -0.2032)
							(mid 0.275042 -0.275042)
							(end 0.2032 -0.3048)
						)
						(arc
							(start -0.2032 -0.3048)
							(mid -0.275042 -0.275042)
							(end -0.3048 -0.2032)
						)
						(arc
							(start -0.3048 0.2032)
							(mid -0.275042 0.275042)
							(end -0.2032 0.3048)
						)
						(arc
							(start 0.2032 0.3048)
							(mid 0.275042 0.275042)
							(end 0.3048 0.2032)
						)
					)
					(width 0)
					(fill yes)
				)
			)
		)
		(pad "2" smd custom
			(at 0 0.4445 180)
			(size 0.1524 0.1524)
			(layers "F.Cu" "F.Mask" "F.Paste")
			(net "GND")
			(options
				(clearance outline)
				(anchor circle)
			)
			(primitives
				(gr_poly
					(pts
						(arc
							(start 0.3048 -0.2032)
							(mid 0.275042 -0.275042)
							(end 0.2032 -0.3048)
						)
						(arc
							(start -0.2032 -0.3048)
							(mid -0.275042 -0.275042)
							(end -0.3048 -0.2032)
						)
						(arc
							(start -0.3048 0.2032)
							(mid -0.275042 0.275042)
							(end -0.2032 0.3048)
						)
						(arc
							(start 0.2032 0.3048)
							(mid 0.275042 0.275042)
							(end 0.3048 0.2032)
						)
					)
					(width 0)
					(fill yes)
				)
			)
		)
	)
	(footprint ""
		(layer "F.Cu")
		(at 66.860166 -84.87156 90)
		(property "Reference" "R478"
			(at 0 0 90)
			(layer "F.SilkS")
			(hide yes)
			(effects
				(font
					(size 1.27 1.27)
				)
			)
		)
		(property "Value" "2MR2F-GP"
			(at 0.064008 -3.993896 90)
			(unlocked yes)
			(layer "F.Fab")
			(hide yes)
			(effects
				(font
					(size 1.016 1.016)
					(thickness 0.1524)
				)
			)
		)
		(property "Device Type" "R402H16"
			(at 0.064008 -5.517896 90)
			(unlocked yes)
			(layer "F.Fab")
			(hide yes)
			(effects
				(font
					(size 1.016 1.016)
					(thickness 0.1524)
				)
			)
		)
		(duplicate_pad_numbers_are_jumpers no)
		(fp_line
			(start 0.508 -0.9398)
			(end -0.508 -0.9398)
			(stroke
				(width 0.1524)
				(type default)
			)
			(layer "F.SilkS")
		)
		(fp_line
			(start -0.508 -0.9398)
			(end -0.508 0.9398)
			(stroke
				(width 0.1524)
				(type default)
			)
			(layer "F.SilkS")
		)
		(fp_rect
			(start -0.508 0.9398)
			(end 0.508 -0.9398)
			(stroke
				(width 0)
				(type default)
			)
			(fill no)
			(layer "F.CrtYd")
		)
		(fp_rect
			(start -0.508 0.9398)
			(end 0.508 -0.9398)
			(stroke
				(width 0)
				(type default)
			)
			(fill no)
			(layer "F.Fab")
		)
		(pad "1" smd custom
			(at 0 -0.4445 90)
			(size 0.1397 0.1397)
			(layers "F.Cu" "F.Mask" "F.Paste")
			(net "HB_OUT_BMC")
			(options
				(clearance outline)
				(anchor circle)
			)
			(primitives
				(gr_poly
					(pts
						(arc
							(start -0.1778 -0.2794)
							(mid -0.249642 -0.249642)
							(end -0.2794 -0.1778)
						)
						(arc
							(start -0.2794 0.1778)
							(mid -0.249642 0.249642)
							(end -0.1778 0.2794)
						)
						(arc
							(start 0.1778 0.2794)
							(mid 0.249642 0.249642)
							(end 0.2794 0.1778)
						)
						(arc
							(start 0.2794 -0.1778)
							(mid 0.249642 -0.249642)
							(end 0.1778 -0.2794)
						)
					)
					(width 0)
					(fill yes)
				)
			)
		)
		(pad "2" smd custom
			(at 0 0.4445 90)
			(size 0.1397 0.1397)
			(layers "F.Cu" "F.Mask" "F.Paste")
			(net "HB_A_IN")
			(options
				(clearance outline)
				(anchor circle)
			)
			(primitives
				(gr_poly
					(pts
						(arc
							(start -0.1778 -0.2794)
							(mid -0.249642 -0.249642)
							(end -0.2794 -0.1778)
						)
						(arc
							(start -0.2794 0.1778)
							(mid -0.249642 0.249642)
							(end -0.1778 0.2794)
						)
						(arc
							(start 0.1778 0.2794)
							(mid 0.249642 0.249642)
							(end 0.2794 0.1778)
						)
						(arc
							(start 0.2794 -0.1778)
							(mid 0.249642 -0.249642)
							(end 0.1778 -0.2794)
						)
					)
					(width 0)
					(fill yes)
				)
			)
		)
	)
	(footprint ""
		(layer "F.Cu")
		(at 25.4 -144.653 -90)
		(property "Reference" "R298"
			(at 0 0 270)
			(layer "F.SilkS")
			(hide yes)
			(effects
				(font
					(size 1.27 1.27)
				)
			)
		)
		(property "Value" "10R2F-L-GP"
			(at 0.064008 -3.993896 270)
			(unlocked yes)
			(layer "F.Fab")
			(hide yes)
			(effects
				(font
					(size 1.016 1.016)
					(thickness 0.1524)
				)
			)
		)
		(property "Device Type" "R402H14"
			(at 0.064008 -5.517896 270)
			(unlocked yes)
			(layer "F.Fab")
			(hide yes)
			(effects
				(font
					(size 1.016 1.016)
					(thickness 0.1524)
				)
			)
		)
		(duplicate_pad_numbers_are_jumpers no)
		(fp_line
			(start -0.508 -0.9398)
			(end -0.508 0.9398)
			(stroke
				(width 0.1524)
				(type default)
			)
			(layer "F.SilkS")
		)
		(fp_line
			(start 0.508 -0.9398)
			(end -0.508 -0.9398)
			(stroke
				(width 0.1524)
				(type default)
			)
			(layer "F.SilkS")
		)
		(fp_rect
			(start -0.508 0.9398)
			(end 0.508 -0.9398)
			(stroke
				(width 0)
				(type default)
			)
			(fill no)
			(layer "F.CrtYd")
		)
		(fp_rect
			(start -0.508 0.9398)
			(end 0.508 -0.9398)
			(stroke
				(width 0)
				(type default)
			)
			(fill no)
			(layer "F.Fab")
		)
		(pad "1" smd custom
			(at 0 -0.4445 270)
			(size 0.1397 0.1397)
			(layers "F.Cu" "F.Mask" "F.Paste")
			(net "OSC2_OUT")
			(options
				(clearance outline)
				(anchor circle)
			)
			(primitives
				(gr_poly
					(pts
						(arc
							(start -0.1778 -0.2794)
							(mid -0.249642 -0.249642)
							(end -0.2794 -0.1778)
						)
						(arc
							(start -0.2794 0.1778)
							(mid -0.249642 0.249642)
							(end -0.1778 0.2794)
						)
						(arc
							(start 0.1778 0.2794)
							(mid 0.249642 0.249642)
							(end 0.2794 0.1778)
						)
						(arc
							(start 0.2794 -0.1778)
							(mid 0.249642 -0.249642)
							(end 0.1778 -0.2794)
						)
					)
					(width 0)
					(fill yes)
				)
			)
		)
		(pad "2" smd custom
			(at 0 0.4445 270)
			(size 0.1397 0.1397)
			(layers "F.Cu" "F.Mask" "F.Paste")
			(net "OSC0_AS_CLKIN")
			(options
				(clearance outline)
				(anchor circle)
			)
			(primitives
				(gr_poly
					(pts
						(arc
							(start -0.1778 -0.2794)
							(mid -0.249642 -0.249642)
							(end -0.2794 -0.1778)
						)
						(arc
							(start -0.2794 0.1778)
							(mid -0.249642 0.249642)
							(end -0.1778 0.2794)
						)
						(arc
							(start 0.1778 0.2794)
							(mid 0.249642 0.249642)
							(end 0.2794 0.1778)
						)
						(arc
							(start 0.2794 -0.1778)
							(mid 0.249642 -0.249642)
							(end 0.1778 -0.2794)
						)
					)
					(width 0)
					(fill yes)
				)
			)
		)
	)
	(footprint ""
		(layer "F.Cu")
		(at 44.323 -143.891)
		(property "Reference" "TP240"
			(at 0 0 0)
			(layer "F.SilkS")
			(hide yes)
			(effects
				(font
					(size 1.27 1.27)
				)
			)
		)
		(property "Value" "TPAD28-2-GP"
			(at -0.0127 -1.6637 0)
			(unlocked yes)
			(layer "F.Fab")
			(hide yes)
			(effects
				(font
					(size 1.016 1.016)
					(thickness 0.1524)
				)
			)
		)
		(property "Device Type" "TPAD28"
			(at -0.0127 -3.1877 0)
			(unlocked yes)
			(layer "F.Fab")
			(hide yes)
			(effects
				(font
					(size 1.016 1.016)
					(thickness 0.1524)
				)
			)
		)
		(duplicate_pad_numbers_are_jumpers no)
		(fp_poly
			(pts
				(arc
					(start 0.3556 0)
					(mid -0.3556 0)
					(end 0.3556 0)
				)
			)
			(stroke
				(width 0)
				(type default)
			)
			(fill no)
			(layer "F.CrtYd")
		)
		(fp_poly
			(pts
				(arc
					(start 0.6096 0)
					(mid -0.6096 0)
					(end 0.6096 0)
				)
			)
			(stroke
				(width 0)
				(type default)
			)
			(fill no)
			(layer "F.Fab")
		)
		(pad "1" smd circle
			(at 0 0)
			(size 0.7112 0.7112)
			(layers "F.Cu" "F.Mask" "F.Paste")
			(net "TP_GPIOP4")
		)
	)
	(footprint ""
		(layer "F.Cu")
		(at 135.96493 -59.755532 180)
		(property "Reference" "R956"
			(at 0 0 180)
			(layer "F.SilkS")
			(hide yes)
			(effects
				(font
					(size 1.27 1.27)
				)
			)
		)
		(property "Value" "33R2J-2-GP"
			(at 0.064008 -3.993896 180)
			(unlocked yes)
			(layer "F.Fab")
			(hide yes)
			(effects
				(font
					(size 1.016 1.016)
					(thickness 0.1524)
				)
			)
		)
		(property "Device Type" "R402H16"
			(at 0.064008 -5.517896 180)
			(unlocked yes)
			(layer "F.Fab")
			(hide yes)
			(effects
				(font
					(size 1.016 1.016)
					(thickness 0.1524)
				)
			)
		)
		(duplicate_pad_numbers_are_jumpers no)
		(fp_line
			(start 0.508 -0.9398)
			(end -0.508 -0.9398)
			(stroke
				(width 0.1524)
				(type default)
			)
			(layer "F.SilkS")
		)
		(fp_line
			(start -0.508 -0.9398)
			(end -0.508 0.9398)
			(stroke
				(width 0.1524)
				(type default)
			)
			(layer "F.SilkS")
		)
		(fp_rect
			(start -0.508 0.9398)
			(end 0.508 -0.9398)
			(stroke
				(width 0)
				(type default)
			)
			(fill no)
			(layer "F.CrtYd")
		)
		(fp_rect
			(start -0.508 0.9398)
			(end 0.508 -0.9398)
			(stroke
				(width 0)
				(type default)
			)
			(fill no)
			(layer "F.Fab")
		)
		(pad "1" smd custom
			(at 0 -0.4445 180)
			(size 0.1397 0.1397)
			(layers "F.Cu" "F.Mask" "F.Paste")
			(net "SPI_DATA0_2")
			(options
				(clearance outline)
				(anchor circle)
			)
			(primitives
				(gr_poly
					(pts
						(arc
							(start -0.1778 -0.2794)
							(mid -0.249642 -0.249642)
							(end -0.2794 -0.1778)
						)
						(arc
							(start -0.2794 0.1778)
							(mid -0.249642 0.249642)
							(end -0.1778 0.2794)
						)
						(arc
							(start 0.1778 0.2794)
							(mid 0.249642 0.249642)
							(end 0.2794 0.1778)
						)
						(arc
							(start 0.2794 -0.1778)
							(mid 0.249642 -0.249642)
							(end 0.1778 -0.2794)
						)
					)
					(width 0)
					(fill yes)
				)
			)
		)
		(pad "2" smd custom
			(at 0 0.4445 180)
			(size 0.1397 0.1397)
			(layers "F.Cu" "F.Mask" "F.Paste")
			(net "SPI_DATA0_2_R")
			(options
				(clearance outline)
				(anchor circle)
			)
			(primitives
				(gr_poly
					(pts
						(arc
							(start -0.1778 -0.2794)
							(mid -0.249642 -0.249642)
							(end -0.2794 -0.1778)
						)
						(arc
							(start -0.2794 0.1778)
							(mid -0.249642 0.249642)
							(end -0.1778 0.2794)
						)
						(arc
							(start 0.1778 0.2794)
							(mid 0.249642 0.249642)
							(end 0.2794 0.1778)
						)
						(arc
							(start 0.2794 -0.1778)
							(mid 0.249642 -0.249642)
							(end 0.1778 -0.2794)
						)
					)
					(width 0)
					(fill yes)
				)
			)
		)
	)
	(footprint ""
		(layer "F.Cu")
		(at 70.993 -36.957 90)
		(property "Reference" "PR25"
			(at 0 0 90)
			(layer "F.SilkS")
			(hide yes)
			(effects
				(font
					(size 1.27 1.27)
				)
			)
		)
		(property "Value" "10KR2F-2-GP"
			(at 0.064008 -3.993896 90)
			(unlocked yes)
			(layer "F.Fab")
			(hide yes)
			(effects
				(font
					(size 1.016 1.016)
					(thickness 0.1524)
				)
			)
		)
		(property "Device Type" "R402H16"
			(at 0.064008 -5.517896 90)
			(unlocked yes)
			(layer "F.Fab")
			(hide yes)
			(effects
				(font
					(size 1.016 1.016)
					(thickness 0.1524)
				)
			)
		)
		(duplicate_pad_numbers_are_jumpers no)
		(fp_line
			(start 0.508 -0.9398)
			(end -0.508 -0.9398)
			(stroke
				(width 0.1524)
				(type default)
			)
			(layer "F.SilkS")
		)
		(fp_line
			(start -0.508 -0.9398)
			(end -0.508 0.9398)
			(stroke
				(width 0.1524)
				(type default)
			)
			(layer "F.SilkS")
		)
		(fp_rect
			(start -0.508 0.9398)
			(end 0.508 -0.9398)
			(stroke
				(width 0)
				(type default)
			)
			(fill no)
			(layer "F.CrtYd")
		)
		(fp_rect
			(start -0.508 0.9398)
			(end 0.508 -0.9398)
			(stroke
				(width 0)
				(type default)
			)
			(fill no)
			(layer "F.Fab")
		)
		(pad "1" smd custom
			(at 0 -0.4445 90)
			(size 0.1397 0.1397)
			(layers "F.Cu" "F.Mask" "F.Paste")
			(net "P3V3_STBY_PG")
			(options
				(clearance outline)
				(anchor circle)
			)
			(primitives
				(gr_poly
					(pts
						(arc
							(start -0.1778 -0.2794)
							(mid -0.249642 -0.249642)
							(end -0.2794 -0.1778)
						)
						(arc
							(start -0.2794 0.1778)
							(mid -0.249642 0.249642)
							(end -0.1778 0.2794)
						)
						(arc
							(start 0.1778 0.2794)
							(mid 0.249642 0.249642)
							(end 0.2794 0.1778)
						)
						(arc
							(start 0.2794 -0.1778)
							(mid 0.249642 -0.249642)
							(end 0.1778 -0.2794)
						)
					)
					(width 0)
					(fill yes)
				)
			)
		)
		(pad "2" smd custom
			(at 0 0.4445 90)
			(size 0.1397 0.1397)
			(layers "F.Cu" "F.Mask" "F.Paste")
			(net "P3V3_STBY")
			(options
				(clearance outline)
				(anchor circle)
			)
			(primitives
				(gr_poly
					(pts
						(arc
							(start -0.1778 -0.2794)
							(mid -0.249642 -0.249642)
							(end -0.2794 -0.1778)
						)
						(arc
							(start -0.2794 0.1778)
							(mid -0.249642 0.249642)
							(end -0.1778 0.2794)
						)
						(arc
							(start 0.1778 0.2794)
							(mid 0.249642 0.249642)
							(end 0.2794 0.1778)
						)
						(arc
							(start 0.2794 -0.1778)
							(mid 0.249642 -0.249642)
							(end 0.1778 -0.2794)
						)
					)
					(width 0)
					(fill yes)
				)
			)
		)
	)
)
